(kicad_pcb
	(version 20260206)
	(generator "pcbnew")
	(generator_version "10.0")
	(general
		(thickness 1.6)
		(legacy_teardrops no)
	)
	(paper "A4")
	(title_block
		(title "Wiwynn_Tioga_Pass_MB.brd")
		(comment 1 "Tioga Pass / footprints 1648-1654 of 4770")
	)
	(layers
		(0 "F.Cu" signal "TOP")
		(4 "In1.Cu" signal "L2GND")
		(6 "In2.Cu" signal "L3")
		(8 "In3.Cu" signal "L4GND")
		(10 "In4.Cu" signal "L5")
		(12 "In5.Cu" signal "L6GND")
		(14 "In6.Cu" signal "L7VCC")
		(16 "In7.Cu" signal "L8VCC")
		(18 "In8.Cu" signal "L9GND")
		(20 "In9.Cu" signal "L10")
		(22 "In10.Cu" signal "L11GND")
		(24 "In11.Cu" signal "L12")
		(26 "In12.Cu" signal "L13GND")
		(2 "B.Cu" signal "BOTTOM")
		(9 "F.Adhes" user "F.Adhesive")
		(11 "B.Adhes" user "B.Adhesive")
		(13 "F.Paste" user "Package Geometry/Pastemask Top")
		(15 "B.Paste" user "Package Geometry/Pastemask Bottom")
		(5 "F.SilkS" user "Ref Des/Silkscreen Top")
		(7 "B.SilkS" user "Ref Des/Silkscreen Bottom")
		(1 "F.Mask" user "Board Geometry/Soldermask Top")
		(3 "B.Mask" user "Board Geometry/Soldermask Bottom")
		(17 "Dwgs.User" user "User.Drawings")
		(19 "Cmts.User" user "User.Comments")
		(21 "Eco1.User" user "User.Eco1")
		(23 "Eco2.User" user "User.Eco2")
		(25 "Edge.Cuts" user "Board Geometry/Outline")
		(27 "Margin" user)
		(31 "F.CrtYd" user "Package Geometry/Place Bound Top")
		(29 "B.CrtYd" user "Package Geometry/Place Bound Bottom")
		(35 "F.Fab" user "Ref Des/Assembly Top")
		(33 "B.Fab" user "Ref Des/Assembly Bottom")
	)
	(footprint ""
		(layer "F.Cu")
		(at 449.69938 -38.2905 90)
		(property "Reference" "R25W23"
			(at 0 0 90)
			(layer "F.SilkS")
			(hide yes)
			(effects
				(font
					(size 1.27 1.27)
				)
			)
		)
		(property "Value" "*"
			(at 0.064008 -4.108196 90)
			(unlocked yes)
			(layer "F.Fab")
			(hide yes)
			(effects
				(font
					(size 1.27 1.016)
					(thickness 0.1524)
				)
			)
		)
		(property "Device Type" "120R2F-GP_RCL_GP-120R2F-GP,64.A"
			(at 0.064008 -5.632196 90)
			(unlocked yes)
			(layer "F.Fab")
			(hide yes)
			(effects
				(font
					(size 1.27 1.016)
					(thickness 0.1524)
				)
			)
		)
		(duplicate_pad_numbers_are_jumpers no)
		(fp_line
			(start 0.508 -0.9398)
			(end -0.508 -0.9398)
			(stroke
				(width 0.1524)
				(type default)
			)
			(layer "F.SilkS")
		)
		(fp_line
			(start -0.508 -0.9398)
			(end -0.508 0.9398)
			(stroke
				(width 0.1524)
				(type default)
			)
			(layer "F.SilkS")
		)
		(fp_rect
			(start -0.508 0.9398)
			(end 0.508 -0.9398)
			(stroke
				(width 0)
				(type default)
			)
			(fill no)
			(layer "F.CrtYd")
		)
		(fp_rect
			(start -0.508 0.9398)
			(end 0.508 -0.9398)
			(stroke
				(width 0)
				(type default)
			)
			(fill no)
			(layer "F.Fab")
		)
		(pad "1" smd custom
			(at 0 -0.4445 90)
			(size 0.1397 0.1397)
			(layers "F.Cu" "F.Mask" "F.Paste")
			(net "GND")
			(options
				(clearance outline)
				(anchor circle)
			)
			(primitives
				(gr_poly
					(pts
						(arc
							(start -0.1778 -0.2794)
							(mid -0.249642 -0.249642)
							(end -0.2794 -0.1778)
						)
						(arc
							(start -0.2794 0.1778)
							(mid -0.249642 0.249642)
							(end -0.1778 0.2794)
						)
						(arc
							(start 0.1778 0.2794)
							(mid 0.249642 0.249642)
							(end 0.2794 0.1778)
						)
						(arc
							(start 0.2794 -0.1778)
							(mid 0.249642 -0.249642)
							(end 0.1778 -0.2794)
						)
					)
					(width 0)
					(fill yes)
				)
			)
		)
		(pad "2" smd custom
			(at 0 0.4445 90)
			(size 0.1397 0.1397)
			(layers "F.Cu" "F.Mask" "F.Paste")
			(net "BMC_M_A11")
			(options
				(clearance outline)
				(anchor circle)
			)
			(primitives
				(gr_poly
					(pts
						(arc
							(start -0.1778 -0.2794)
							(mid -0.249642 -0.249642)
							(end -0.2794 -0.1778)
						)
						(arc
							(start -0.2794 0.1778)
							(mid -0.249642 0.249642)
							(end -0.1778 0.2794)
						)
						(arc
							(start 0.1778 0.2794)
							(mid 0.249642 0.249642)
							(end 0.2794 0.1778)
						)
						(arc
							(start 0.2794 -0.1778)
							(mid 0.249642 -0.249642)
							(end 0.1778 -0.2794)
						)
					)
					(width 0)
					(fill yes)
				)
			)
		)
	)
	(footprint ""
		(layer "F.Cu")
		(at 363.249718 -72.133206 180)
		(property "Reference" "R7D42"
			(at 0 0 180)
			(layer "F.SilkS")
			(hide yes)
			(effects
				(font
					(size 1.27 1.27)
				)
			)
		)
		(property "Value" ""
			(at 0 0 180)
			(layer "F.Fab")
			(effects
				(font
					(size 1.27 1.27)
				)
			)
		)
		(duplicate_pad_numbers_are_jumpers no)
		(fp_poly
			(pts
				(xy -0.2794 -0.1016) (xy 0.2794 -0.1016) (xy 0.2794 0.9906) (xy -0.2794 0.9906)
			)
			(stroke
				(width 0)
				(type default)
			)
			(fill no)
			(layer "F.CrtYd")
		)
		(fp_line
			(start 0.2794 0.9906)
			(end 0.2794 -0.1016)
			(stroke
				(width 0.1)
				(type default)
			)
			(layer "F.Fab")
		)
		(fp_line
			(start 0.2794 -0.1016)
			(end -0.2794 -0.1016)
			(stroke
				(width 0.1)
				(type default)
			)
			(layer "F.Fab")
		)
		(fp_line
			(start -0.2794 0.9906)
			(end 0.2794 0.9906)
			(stroke
				(width 0.1)
				(type default)
			)
			(layer "F.Fab")
		)
		(fp_line
			(start -0.2794 -0.1016)
			(end -0.2794 0.9906)
			(stroke
				(width 0.1)
				(type default)
			)
			(layer "F.Fab")
		)
		(pad "1" smd rect
			(at 0 0 180)
			(size 0.508 0.508)
			(layers "F.Cu" "F.Mask" "F.Paste")
			(net "P3V3_STBY")
		)
		(pad "2" smd rect
			(at 0 0.889 180)
			(size 0.508 0.508)
			(layers "F.Cu" "F.Mask" "F.Paste")
			(net "PU_FAB2_MARKER_CPLD")
		)
		(zone
			(layer "F.Cu")
			(hatch none 0.5)
			(connect_pads
				(clearance 0)
			)
			(min_thickness 0.25)
			(keepout
				(tracks not_allowed)
				(vias allowed)
				(pads allowed)
				(copperpour not_allowed)
				(footprints allowed)
			)
			(placement
				(enabled no)
				(sheetname "")
			)
			(fill
				(thermal_gap 0.5)
				(thermal_bridge_width 0.5)
				(island_removal_mode 0)
			)
			(polygon
				(pts
					(xy 363.503718 -72.768206) (xy 362.995718 -72.768206) (xy 362.995718 -72.387206) (xy 363.503718 -72.387206)
				)
			)
		)
		(zone
			(layer "F.Cu")
			(hatch none 0.5)
			(connect_pads
				(clearance 0)
			)
			(min_thickness 0.25)
			(keepout
				(tracks allowed)
				(vias not_allowed)
				(pads allowed)
				(copperpour not_allowed)
				(footprints allowed)
			)
			(placement
				(enabled no)
				(sheetname "")
			)
			(fill
				(thermal_gap 0.5)
				(thermal_bridge_width 0.5)
				(island_removal_mode 0)
			)
			(polygon
				(pts
					(xy 363.503718 -72.387206) (xy 362.995718 -72.387206) (xy 362.995718 -72.768206) (xy 363.503718 -72.768206)
				)
			)
		)
	)
	(footprint ""
		(layer "F.Cu")
		(at 357.443532 12.003278 -90)
		(property "Reference" "T1P22"
			(at 0 0 270)
			(layer "F.SilkS")
			(hide yes)
			(effects
				(font
					(size 1.27 1.27)
				)
			)
		)
		(property "Value" "*"
			(at -3.302 1.12395 270)
			(unlocked yes)
			(layer "F.Fab")
			(hide yes)
			(effects
				(font
					(size 0.889 0.889)
					(thickness 0.1524)
				)
			)
		)
		(property "Device Type" "TPAD-DIFF-4P-GP_DISCRET-GB3-TPA"
			(at -3.302 -0.40005 270)
			(unlocked yes)
			(layer "F.Fab")
			(hide yes)
			(effects
				(font
					(size 0.889 0.889)
					(thickness 0.1524)
				)
			)
		)
		(duplicate_pad_numbers_are_jumpers no)
		(fp_line
			(start -2.286 2.286)
			(end 2.286 2.286)
			(stroke
				(width 0.1524)
				(type default)
			)
			(layer "F.SilkS")
		)
		(fp_line
			(start 2.286 2.286)
			(end 2.286 -2.286)
			(stroke
				(width 0.1524)
				(type default)
			)
			(layer "F.SilkS")
		)
		(fp_line
			(start -2.286 -2.286)
			(end -2.286 2.286)
			(stroke
				(width 0.1524)
				(type default)
			)
			(layer "F.SilkS")
		)
		(fp_line
			(start 2.286 -2.286)
			(end -2.286 -2.286)
			(stroke
				(width 0.1524)
				(type default)
			)
			(layer "F.SilkS")
		)
		(fp_line
			(start -2.413 -2.413)
			(end -2.413 -1.143)
			(stroke
				(width 0.4064)
				(type default)
			)
			(layer "F.SilkS")
		)
		(fp_line
			(start -1.143 -2.413)
			(end -2.413 -2.413)
			(stroke
				(width 0.4064)
				(type default)
			)
			(layer "F.SilkS")
		)
		(fp_rect
			(start -2.54 2.54)
			(end 2.54 -2.54)
			(stroke
				(width 0)
				(type default)
			)
			(fill no)
			(layer "F.CrtYd")
		)
		(fp_rect
			(start -2.54 2.54)
			(end 2.54 -2.54)
			(stroke
				(width 0)
				(type default)
			)
			(fill no)
			(layer "F.Fab")
		)
		(pad "1" thru_hole circle
			(at -1.27 -1.27 270)
			(size 1.524 1.524)
			(drill 0.9144)
			(layers "*.Cu" "*.Mask")
			(remove_unused_layers no)
			(net "L10_100OHM_6INCH_DP")
			(clearance -0.0508)
			(thermal_gap 0.127)
			(padstack
				(mode front_inner_back)
				(layer "Inner"
					(shape circle)
					(size 1.1684 1.1684)
					(clearance 0.127)
				)
				(layer "B.Cu"
					(shape circle)
					(size 1.524 1.524)
					(clearance -0.0508)
				)
			)
		)
		(pad "2" thru_hole circle
			(at 1.27 -1.27 270)
			(size 1.524 1.524)
			(drill 0.9144)
			(layers "*.Cu" "*.Mask")
			(remove_unused_layers no)
			(net "L10_100OHM_6INCH_DN")
			(clearance -0.0508)
			(thermal_gap 0.127)
			(padstack
				(mode front_inner_back)
				(layer "Inner"
					(shape circle)
					(size 1.1684 1.1684)
					(clearance 0.127)
				)
				(layer "B.Cu"
					(shape circle)
					(size 1.524 1.524)
					(clearance -0.0508)
				)
			)
		)
		(pad "GND1" thru_hole rect
			(at -1.27 1.27 270)
			(size 1.524 1.524)
			(drill 0.9144)
			(layers "*.Cu" "*.Mask")
			(remove_unused_layers no)
			(net "GND")
			(clearance -0.0508)
			(thermal_gap 0.127)
			(padstack
				(mode front_inner_back)
				(layer "Inner"
					(shape circle)
					(size 1.1684 1.1684)
					(clearance 0.127)
				)
				(layer "B.Cu"
					(shape rect)
					(size 1.524 1.524)
					(clearance -0.0508)
				)
			)
		)
		(pad "GND2" thru_hole rect
			(at 1.27 1.27 270)
			(size 1.524 1.524)
			(drill 0.9144)
			(layers "*.Cu" "*.Mask")
			(remove_unused_layers no)
			(net "GND")
			(clearance -0.0508)
			(thermal_gap 0.127)
			(padstack
				(mode front_inner_back)
				(layer "Inner"
					(shape circle)
					(size 1.1684 1.1684)
					(clearance 0.127)
				)
				(layer "B.Cu"
					(shape rect)
					(size 1.524 1.524)
					(clearance -0.0508)
				)
			)
		)
	)
	(footprint ""
		(layer "F.Cu")
		(at 173.9265 -67.945 90)
		(property "Reference" "C4D40"
			(at 0 0 90)
			(layer "F.SilkS")
			(hide yes)
			(effects
				(font
					(size 1.27 1.27)
				)
			)
		)
		(property "Value" ""
			(at 0 0 90)
			(layer "F.Fab")
			(effects
				(font
					(size 1.27 1.27)
				)
			)
		)
		(duplicate_pad_numbers_are_jumpers no)
		(fp_poly
			(pts
				(xy 0.3048 -0.1016) (xy 0.3048 0.9906) (xy -0.3048 0.9906) (xy -0.3048 -0.1016)
			)
			(stroke
				(width 0)
				(type default)
			)
			(fill no)
			(layer "F.CrtYd")
		)
		(fp_line
			(start 0.3048 -0.1016)
			(end -0.3048 -0.1016)
			(stroke
				(width 0.1)
				(type default)
			)
			(layer "F.Fab")
		)
		(fp_line
			(start -0.3048 -0.1016)
			(end -0.3048 0.9906)
			(stroke
				(width 0.1)
				(type default)
			)
			(layer "F.Fab")
		)
		(fp_line
			(start 0.3048 0.9906)
			(end 0.3048 -0.1016)
			(stroke
				(width 0.1)
				(type default)
			)
			(layer "F.Fab")
		)
		(fp_line
			(start -0.3048 0.9906)
			(end 0.3048 0.9906)
			(stroke
				(width 0.1)
				(type default)
			)
			(layer "F.Fab")
		)
		(pad "1" smd rect
			(at 0 0 90)
			(size 0.508 0.508)
			(layers "F.Cu" "F.Mask" "F.Paste")
			(net "VR_PVCCIO_CPU1_VINSEN")
		)
		(pad "2" smd rect
			(at 0 0.889 90)
			(size 0.508 0.508)
			(layers "F.Cu" "F.Mask" "F.Paste")
			(net "GND")
		)
		(zone
			(layer "F.Cu")
			(hatch none 0.5)
			(connect_pads
				(clearance 0)
			)
			(min_thickness 0.25)
			(keepout
				(tracks allowed)
				(vias not_allowed)
				(pads allowed)
				(copperpour not_allowed)
				(footprints allowed)
			)
			(placement
				(enabled no)
				(sheetname "")
			)
			(fill
				(thermal_gap 0.5)
				(thermal_bridge_width 0.5)
				(island_removal_mode 0)
			)
			(polygon
				(pts
					(xy 174.1805 -67.691) (xy 174.1805 -68.199) (xy 174.5615 -68.199) (xy 174.5615 -67.691)
				)
			)
		)
		(zone
			(layer "F.Cu")
			(hatch none 0.5)
			(connect_pads
				(clearance 0)
			)
			(min_thickness 0.25)
			(keepout
				(tracks not_allowed)
				(vias allowed)
				(pads allowed)
				(copperpour not_allowed)
				(footprints allowed)
			)
			(placement
				(enabled no)
				(sheetname "")
			)
			(fill
				(thermal_gap 0.5)
				(thermal_bridge_width 0.5)
				(island_removal_mode 0)
			)
			(polygon
				(pts
					(xy 174.5615 -67.691) (xy 174.5615 -68.199) (xy 174.1805 -68.199) (xy 174.1805 -67.691)
				)
			)
		)
	)
	(footprint ""
		(layer "F.Cu")
		(at 381.576072 -154.416506)
		(property "Reference" "C7A41"
			(at 0 0 0)
			(layer "F.SilkS")
			(hide yes)
			(effects
				(font
					(size 1.27 1.27)
				)
			)
		)
		(property "Value" ""
			(at 0 0 0)
			(layer "F.Fab")
			(effects
				(font
					(size 1.27 1.27)
				)
			)
		)
		(duplicate_pad_numbers_are_jumpers no)
		(fp_poly
			(pts
				(xy 0.3048 -0.1016) (xy 0.3048 0.9906) (xy -0.3048 0.9906) (xy -0.3048 -0.1016)
			)
			(stroke
				(width 0)
				(type default)
			)
			(fill no)
			(layer "F.CrtYd")
		)
		(fp_line
			(start -0.3048 -0.1016)
			(end -0.3048 0.9906)
			(stroke
				(width 0.1)
				(type default)
			)
			(layer "F.Fab")
		)
		(fp_line
			(start -0.3048 0.9906)
			(end 0.3048 0.9906)
			(stroke
				(width 0.1)
				(type default)
			)
			(layer "F.Fab")
		)
		(fp_line
			(start 0.3048 -0.1016)
			(end -0.3048 -0.1016)
			(stroke
				(width 0.1)
				(type default)
			)
			(layer "F.Fab")
		)
		(fp_line
			(start 0.3048 0.9906)
			(end 0.3048 -0.1016)
			(stroke
				(width 0.1)
				(type default)
			)
			(layer "F.Fab")
		)
		(pad "1" smd rect
			(at 0 0)
			(size 0.508 0.508)
			(layers "F.Cu" "F.Mask" "F.Paste")
			(net "P5V_STBY")
		)
		(pad "2" smd rect
			(at 0 0.889)
			(size 0.508 0.508)
			(layers "F.Cu" "F.Mask" "F.Paste")
			(net "GND")
		)
		(zone
			(layer "F.Cu")
			(hatch none 0.5)
			(connect_pads
				(clearance 0)
			)
			(min_thickness 0.25)
			(keepout
				(tracks allowed)
				(vias not_allowed)
				(pads allowed)
				(copperpour not_allowed)
				(footprints allowed)
			)
			(placement
				(enabled no)
				(sheetname "")
			)
			(fill
				(thermal_gap 0.5)
				(thermal_bridge_width 0.5)
				(island_removal_mode 0)
			)
			(polygon
				(pts
					(xy 381.322072 -154.162506) (xy 381.830072 -154.162506) (xy 381.830072 -153.781506) (xy 381.322072 -153.781506)
				)
			)
		)
		(zone
			(layer "F.Cu")
			(hatch none 0.5)
			(connect_pads
				(clearance 0)
			)
			(min_thickness 0.25)
			(keepout
				(tracks not_allowed)
				(vias allowed)
				(pads allowed)
				(copperpour not_allowed)
				(footprints allowed)
			)
			(placement
				(enabled no)
				(sheetname "")
			)
			(fill
				(thermal_gap 0.5)
				(thermal_bridge_width 0.5)
				(island_removal_mode 0)
			)
			(polygon
				(pts
					(xy 381.322072 -153.781506) (xy 381.830072 -153.781506) (xy 381.830072 -154.162506) (xy 381.322072 -154.162506)
				)
			)
		)
	)
	(footprint ""
		(layer "F.Cu")
		(at 98.524568 -84.709)
		(property "Reference" "C2D7"
			(at 0 0 0)
			(layer "F.SilkS")
			(hide yes)
			(effects
				(font
					(size 1.27 1.27)
				)
			)
		)
		(property "Value" ""
			(at 0 0 0)
			(layer "F.Fab")
			(effects
				(font
					(size 1.27 1.27)
				)
			)
		)
		(duplicate_pad_numbers_are_jumpers no)
		(fp_poly
			(pts
				(xy -0.4953 -0.2032) (xy 0.4953 -0.2032) (xy 0.4953 1.6002) (xy -0.4953 1.6002)
			)
			(stroke
				(width 0)
				(type default)
			)
			(fill no)
			(layer "F.CrtYd")
		)
		(fp_line
			(start -0.4953 -0.2032)
			(end 0.4953 -0.2032)
			(stroke
				(width 0.1)
				(type default)
			)
			(layer "F.Fab")
		)
		(fp_line
			(start -0.4953 1.6002)
			(end -0.4953 -0.2032)
			(stroke
				(width 0.1)
				(type default)
			)
			(layer "F.Fab")
		)
		(fp_line
			(start 0.4953 -0.2032)
			(end 0.4953 1.6002)
			(stroke
				(width 0.1)
				(type default)
			)
			(layer "F.Fab")
		)
		(fp_line
			(start 0.4953 1.6002)
			(end -0.4953 1.6002)
			(stroke
				(width 0.1)
				(type default)
			)
			(layer "F.Fab")
		)
		(pad "1" smd rect
			(at 0 0)
			(size 0.762 0.889)
			(layers "F.Cu" "F.Mask" "F.Paste")
			(net "PVDDQ_KLM")
		)
		(pad "2" smd rect
			(at 0 1.397)
			(size 0.762 0.889)
			(layers "F.Cu" "F.Mask" "F.Paste")
			(net "GND")
		)
		(zone
			(layer "F.Cu")
			(hatch none 0.5)
			(connect_pads
				(clearance 0)
			)
			(min_thickness 0.25)
			(keepout
				(tracks not_allowed)
				(vias allowed)
				(pads allowed)
				(copperpour not_allowed)
				(footprints allowed)
			)
			(placement
				(enabled no)
				(sheetname "")
			)
			(fill
				(thermal_gap 0.5)
				(thermal_bridge_width 0.5)
				(island_removal_mode 0)
			)
			(polygon
				(pts
					(xy 98.143568 -84.2645) (xy 98.905568 -84.2645) (xy 98.905568 -83.7565) (xy 98.143568 -83.7565)
				)
			)
		)
	)
	(footprint ""
		(layer "F.Cu")
		(at 13.8938 -26.797 90)
		(property "Reference" "C1F15"
			(at 0 0 90)
			(layer "F.SilkS")
			(hide yes)
			(effects
				(font
					(size 1.27 1.27)
				)
			)
		)
		(property "Value" ""
			(at 0 0 90)
			(layer "F.Fab")
			(effects
				(font
					(size 1.27 1.27)
				)
			)
		)
		(duplicate_pad_numbers_are_jumpers no)
		(fp_rect
			(start -0.3048 -0.1016)
			(end 0.3048 0.9906)
			(stroke
				(width 0)
				(type default)
			)
			(fill no)
			(layer "F.CrtYd")
		)
		(fp_line
			(start 0.3048 -0.1016)
			(end -0.3048 -0.1016)
			(stroke
				(width 0.1)
				(type default)
			)
			(layer "F.Fab")
		)
		(fp_line
			(start -0.3048 -0.1016)
			(end -0.3048 0.9906)
			(stroke
				(width 0.1)
				(type default)
			)
			(layer "F.Fab")
		)
		(fp_line
			(start 0.3048 0.9906)
			(end 0.3048 -0.1016)
			(stroke
				(width 0.1)
				(type default)
			)
			(layer "F.Fab")
		)
		(fp_line
			(start -0.3048 0.9906)
			(end 0.3048 0.9906)
			(stroke
				(width 0.1)
				(type default)
			)
			(layer "F.Fab")
		)
		(pad "1" smd rect
			(at 0 0 90)
			(size 0.508 0.508)
			(layers "F.Cu" "F.Mask" "F.Paste")
			(net "P3E_CPU1_PE3_MP_C_TXN<2>")
		)
		(pad "2" smd rect
			(at 0 0.889 90)
			(size 0.508 0.508)
			(layers "F.Cu" "F.Mask" "F.Paste")
			(net "P3E_CPU1_PE3_MP_TXN<2>")
		)
		(zone
			(layer "F.Cu")
			(hatch none 0.5)
			(connect_pads
				(clearance 0)
			)
			(min_thickness 0.25)
			(keepout
				(tracks not_allowed)
				(vias allowed)
				(pads allowed)
				(copperpour not_allowed)
				(footprints allowed)
			)
			(placement
				(enabled no)
				(sheetname "")
			)
			(fill
				(thermal_gap 0.5)
				(thermal_bridge_width 0.5)
				(island_removal_mode 0)
			)
			(polygon
				(pts
					(xy 14.1478 -26.543) (xy 14.5288 -26.543) (xy 14.5288 -27.051) (xy 14.1478 -27.051)
				)
			)
		)
		(zone
			(layer "F.Cu")
			(hatch none 0.5)
			(connect_pads
				(clearance 0)
			)
			(min_thickness 0.25)
			(keepout
				(tracks allowed)
				(vias not_allowed)
				(pads allowed)
				(copperpour not_allowed)
				(footprints allowed)
			)
			(placement
				(enabled no)
				(sheetname "")
			)
			(fill
				(thermal_gap 0.5)
				(thermal_bridge_width 0.5)
				(island_removal_mode 0)
			)
			(polygon
				(pts
					(xy 14.1478 -26.543) (xy 14.5288 -26.543) (xy 14.5288 -27.051) (xy 14.1478 -27.051)
				)
			)
		)
	)
)
